(kicad_pcb
	(version 20260206)
	(generator "pcbnew")
	(generator_version "10.0")
	(general
		(thickness 1.6)
		(legacy_teardrops no)
	)
	(paper "A4")
	(title_block
		(title "peb — Lightning_PEB_BRD.brd")
		(comment 1 "Lightning (Wiwynn / Facebook NVMe JBOF) / footprints 81-84 of 2563")
	)
	(layers
		(0 "F.Cu" signal "TOP")
		(4 "In1.Cu" signal "L2GND")
		(6 "In2.Cu" signal "L3")
		(8 "In3.Cu" signal "L4VCC")
		(10 "In4.Cu" signal "L5VCC")
		(12 "In5.Cu" signal "L6")
		(14 "In6.Cu" signal "L7GND")
		(2 "B.Cu" signal "BOTTOM")
		(9 "F.Adhes" user "F.Adhesive")
		(11 "B.Adhes" user "B.Adhesive")
		(13 "F.Paste" user "Package Geometry/Pastemask Top")
		(15 "B.Paste" user "Package Geometry/Pastemask Bottom")
		(5 "F.SilkS" user "Ref Des/Silkscreen Top")
		(7 "B.SilkS" user "Ref Des/Silkscreen Bottom")
		(1 "F.Mask" user "Board Geometry/Soldermask Top")
		(3 "B.Mask" user "Board Geometry/Soldermask Bottom")
		(17 "Dwgs.User" user "User.Drawings")
		(19 "Cmts.User" user "User.Comments")
		(21 "Eco1.User" user "User.Eco1")
		(23 "Eco2.User" user "User.Eco2")
		(25 "Edge.Cuts" user "Board Geometry/Outline")
		(27 "Margin" user)
		(31 "F.CrtYd" user "Package Geometry/Place Bound Top")
		(29 "B.CrtYd" user "Package Geometry/Place Bound Bottom")
		(35 "F.Fab" user "Ref Des/Assembly Top")
		(33 "B.Fab" user "Ref Des/Assembly Bottom")
	)
	(footprint ""
		(layer "F.Cu")
		(at 327.533 -99.568 180)
		(property "Reference" "R4173"
			(at 0 0 180)
			(layer "F.SilkS")
			(hide yes)
			(effects
				(font
					(size 1.27 1.27)
				)
			)
		)
		(property "Value" "4K7R2F-GP"
			(at 0.064008 -3.993896 180)
			(unlocked yes)
			(layer "F.Fab")
			(hide yes)
			(effects
				(font
					(size 1.016 1.016)
					(thickness 0.1524)
				)
			)
		)
		(property "Device Type" "R402H16"
			(at 0.064008 -5.517896 180)
			(unlocked yes)
			(layer "F.Fab")
			(hide yes)
			(effects
				(font
					(size 1.016 1.016)
					(thickness 0.1524)
				)
			)
		)
		(duplicate_pad_numbers_are_jumpers no)
		(fp_line
			(start 0.508 -0.9398)
			(end -0.508 -0.9398)
			(stroke
				(width 0.1524)
				(type default)
			)
			(layer "F.SilkS")
		)
		(fp_line
			(start -0.508 -0.9398)
			(end -0.508 0.9398)
			(stroke
				(width 0.1524)
				(type default)
			)
			(layer "F.SilkS")
		)
		(fp_rect
			(start -0.508 0.9398)
			(end 0.508 -0.9398)
			(stroke
				(width 0)
				(type default)
			)
			(fill no)
			(layer "F.CrtYd")
		)
		(fp_rect
			(start -0.508 0.9398)
			(end 0.508 -0.9398)
			(stroke
				(width 0)
				(type default)
			)
			(fill no)
			(layer "F.Fab")
		)
		(pad "1" smd custom
			(at 0 -0.4445 180)
			(size 0.1397 0.1397)
			(layers "F.Cu" "F.Mask" "F.Paste")
			(net "VS5_LED")
			(options
				(clearance outline)
				(anchor circle)
			)
			(primitives
				(gr_poly
					(pts
						(arc
							(start -0.1778 -0.2794)
							(mid -0.249642 -0.249642)
							(end -0.2794 -0.1778)
						)
						(arc
							(start -0.2794 0.1778)
							(mid -0.249642 0.249642)
							(end -0.1778 0.2794)
						)
						(arc
							(start 0.1778 0.2794)
							(mid 0.249642 0.249642)
							(end 0.2794 0.1778)
						)
						(arc
							(start 0.2794 -0.1778)
							(mid 0.249642 -0.249642)
							(end 0.1778 -0.2794)
						)
					)
					(width 0)
					(fill yes)
				)
			)
		)
		(pad "2" smd custom
			(at 0 0.4445 180)
			(size 0.1397 0.1397)
			(layers "F.Cu" "F.Mask" "F.Paste")
			(net "P3V3_STBY")
			(options
				(clearance outline)
				(anchor circle)
			)
			(primitives
				(gr_poly
					(pts
						(arc
							(start -0.1778 -0.2794)
							(mid -0.249642 -0.249642)
							(end -0.2794 -0.1778)
						)
						(arc
							(start -0.2794 0.1778)
							(mid -0.249642 0.249642)
							(end -0.1778 0.2794)
						)
						(arc
							(start 0.1778 0.2794)
							(mid 0.249642 0.249642)
							(end 0.2794 0.1778)
						)
						(arc
							(start 0.2794 -0.1778)
							(mid 0.249642 -0.249642)
							(end 0.1778 -0.2794)
						)
					)
					(width 0)
					(fill yes)
				)
			)
		)
	)
	(footprint ""
		(layer "F.Cu")
		(at 159.512 -85.2424 180)
		(property "Reference" "R75"
			(at 0 0 180)
			(layer "F.SilkS")
			(hide yes)
			(effects
				(font
					(size 1.27 1.27)
				)
			)
		)
		(property "Value" "0R2J-2-GP"
			(at 0.064008 -3.993896 180)
			(unlocked yes)
			(layer "F.Fab")
			(hide yes)
			(effects
				(font
					(size 1.016 1.016)
					(thickness 0.1524)
				)
			)
		)
		(property "Device Type" "R402H16"
			(at 0.064008 -5.517896 180)
			(unlocked yes)
			(layer "F.Fab")
			(hide yes)
			(effects
				(font
					(size 1.016 1.016)
					(thickness 0.1524)
				)
			)
		)
		(duplicate_pad_numbers_are_jumpers no)
		(fp_line
			(start 0.508 -0.9398)
			(end -0.508 -0.9398)
			(stroke
				(width 0.1524)
				(type default)
			)
			(layer "F.SilkS")
		)
		(fp_line
			(start -0.508 -0.9398)
			(end -0.508 0.9398)
			(stroke
				(width 0.1524)
				(type default)
			)
			(layer "F.SilkS")
		)
		(fp_rect
			(start -0.508 0.9398)
			(end 0.508 -0.9398)
			(stroke
				(width 0)
				(type default)
			)
			(fill no)
			(layer "F.CrtYd")
		)
		(fp_rect
			(start -0.508 0.9398)
			(end 0.508 -0.9398)
			(stroke
				(width 0)
				(type default)
			)
			(fill no)
			(layer "F.Fab")
		)
		(pad "1" smd custom
			(at 0 -0.4445 180)
			(size 0.1397 0.1397)
			(layers "F.Cu" "F.Mask" "F.Paste")
			(net "BMC_I2C5_D_PEB_SDA")
			(options
				(clearance outline)
				(anchor circle)
			)
			(primitives
				(gr_poly
					(pts
						(arc
							(start -0.1778 -0.2794)
							(mid -0.249642 -0.249642)
							(end -0.2794 -0.1778)
						)
						(arc
							(start -0.2794 0.1778)
							(mid -0.249642 0.249642)
							(end -0.1778 0.2794)
						)
						(arc
							(start 0.1778 0.2794)
							(mid 0.249642 0.249642)
							(end 0.2794 0.1778)
						)
						(arc
							(start 0.2794 -0.1778)
							(mid 0.249642 -0.249642)
							(end 0.1778 -0.2794)
						)
					)
					(width 0)
					(fill yes)
				)
			)
		)
		(pad "2" smd custom
			(at 0 0.4445 180)
			(size 0.1397 0.1397)
			(layers "F.Cu" "F.Mask" "F.Paste")
			(net "CLKGEN_SDA")
			(options
				(clearance outline)
				(anchor circle)
			)
			(primitives
				(gr_poly
					(pts
						(arc
							(start -0.1778 -0.2794)
							(mid -0.249642 -0.249642)
							(end -0.2794 -0.1778)
						)
						(arc
							(start -0.2794 0.1778)
							(mid -0.249642 0.249642)
							(end -0.1778 0.2794)
						)
						(arc
							(start 0.1778 0.2794)
							(mid 0.249642 0.249642)
							(end 0.2794 0.1778)
						)
						(arc
							(start 0.2794 -0.1778)
							(mid 0.249642 -0.249642)
							(end 0.1778 -0.2794)
						)
					)
					(width 0)
					(fill yes)
				)
			)
		)
	)
	(footprint ""
		(layer "F.Cu")
		(at 24.5618 -119.7356)
		(property "Reference" "R684"
			(at 0 0 0)
			(layer "F.SilkS")
			(hide yes)
			(effects
				(font
					(size 1.27 1.27)
				)
			)
		)
		(property "Value" "0R2J-2-GP"
			(at 0.064008 -3.993896 0)
			(unlocked yes)
			(layer "F.Fab")
			(hide yes)
			(effects
				(font
					(size 1.016 1.016)
					(thickness 0.1524)
				)
			)
		)
		(property "Device Type" "R402H16"
			(at 0.064008 -5.517896 0)
			(unlocked yes)
			(layer "F.Fab")
			(hide yes)
			(effects
				(font
					(size 1.016 1.016)
					(thickness 0.1524)
				)
			)
		)
		(duplicate_pad_numbers_are_jumpers no)
		(fp_line
			(start -0.508 -0.9398)
			(end -0.508 0.9398)
			(stroke
				(width 0.1524)
				(type default)
			)
			(layer "F.SilkS")
		)
		(fp_line
			(start 0.508 -0.9398)
			(end -0.508 -0.9398)
			(stroke
				(width 0.1524)
				(type default)
			)
			(layer "F.SilkS")
		)
		(fp_rect
			(start -0.508 0.9398)
			(end 0.508 -0.9398)
			(stroke
				(width 0)
				(type default)
			)
			(fill no)
			(layer "F.CrtYd")
		)
		(fp_rect
			(start -0.508 0.9398)
			(end 0.508 -0.9398)
			(stroke
				(width 0)
				(type default)
			)
			(fill no)
			(layer "F.Fab")
		)
		(pad "1" smd custom
			(at 0 -0.4445)
			(size 0.1397 0.1397)
			(layers "F.Cu" "F.Mask" "F.Paste")
			(net "SPICS0_N_R")
			(options
				(clearance outline)
				(anchor circle)
			)
			(primitives
				(gr_poly
					(pts
						(arc
							(start -0.1778 -0.2794)
							(mid -0.249642 -0.249642)
							(end -0.2794 -0.1778)
						)
						(arc
							(start -0.2794 0.1778)
							(mid -0.249642 0.249642)
							(end -0.1778 0.2794)
						)
						(arc
							(start 0.1778 0.2794)
							(mid 0.249642 0.249642)
							(end 0.2794 0.1778)
						)
						(arc
							(start 0.2794 -0.1778)
							(mid 0.249642 -0.249642)
							(end 0.1778 -0.2794)
						)
					)
					(width 0)
					(fill yes)
				)
			)
		)
		(pad "2" smd custom
			(at 0 0.4445)
			(size 0.1397 0.1397)
			(layers "F.Cu" "F.Mask" "F.Paste")
			(net "SPICS0_N")
			(options
				(clearance outline)
				(anchor circle)
			)
			(primitives
				(gr_poly
					(pts
						(arc
							(start -0.1778 -0.2794)
							(mid -0.249642 -0.249642)
							(end -0.2794 -0.1778)
						)
						(arc
							(start -0.2794 0.1778)
							(mid -0.249642 0.249642)
							(end -0.1778 0.2794)
						)
						(arc
							(start 0.1778 0.2794)
							(mid 0.249642 0.249642)
							(end 0.2794 0.1778)
						)
						(arc
							(start 0.2794 -0.1778)
							(mid 0.249642 -0.249642)
							(end 0.1778 -0.2794)
						)
					)
					(width 0)
					(fill yes)
				)
			)
		)
	)
	(footprint ""
		(layer "F.Cu")
		(at 276.607016 -9.241282 90)
		(property "Reference" "R2909"
			(at 0 0 90)
			(layer "F.SilkS")
			(hide yes)
			(effects
				(font
					(size 1.27 1.27)
				)
			)
		)
		(property "Value" "0R2J-2-GP"
			(at 0.064008 -3.993896 90)
			(unlocked yes)
			(layer "F.Fab")
			(hide yes)
			(effects
				(font
					(size 1.016 1.016)
					(thickness 0.1524)
				)
			)
		)
		(property "Device Type" "R402H16"
			(at 0.064008 -5.517896 90)
			(unlocked yes)
			(layer "F.Fab")
			(hide yes)
			(effects
				(font
					(size 1.016 1.016)
					(thickness 0.1524)
				)
			)
		)
		(duplicate_pad_numbers_are_jumpers no)
		(fp_line
			(start 0.508 -0.9398)
			(end -0.508 -0.9398)
			(stroke
				(width 0.1524)
				(type default)
			)
			(layer "F.SilkS")
		)
		(fp_line
			(start -0.508 -0.9398)
			(end -0.508 0.9398)
			(stroke
				(width 0.1524)
				(type default)
			)
			(layer "F.SilkS")
		)
		(fp_rect
			(start -0.508 0.9398)
			(end 0.508 -0.9398)
			(stroke
				(width 0)
				(type default)
			)
			(fill no)
			(layer "F.CrtYd")
		)
		(fp_rect
			(start -0.508 0.9398)
			(end 0.508 -0.9398)
			(stroke
				(width 0)
				(type default)
			)
			(fill no)
			(layer "F.Fab")
		)
		(pad "1" smd custom
			(at 0 -0.4445 90)
			(size 0.1397 0.1397)
			(layers "F.Cu" "F.Mask" "F.Paste")
			(net "BMC_I2C11_MINI5_SDA")
			(options
				(clearance outline)
				(anchor circle)
			)
			(primitives
				(gr_poly
					(pts
						(arc
							(start -0.1778 -0.2794)
							(mid -0.249642 -0.249642)
							(end -0.2794 -0.1778)
						)
						(arc
							(start -0.2794 0.1778)
							(mid -0.249642 0.249642)
							(end -0.1778 0.2794)
						)
						(arc
							(start 0.1778 0.2794)
							(mid 0.249642 0.249642)
							(end 0.2794 0.1778)
						)
						(arc
							(start 0.2794 -0.1778)
							(mid 0.249642 -0.249642)
							(end 0.1778 -0.2794)
						)
					)
					(width 0)
					(fill yes)
				)
			)
		)
		(pad "2" smd custom
			(at 0 0.4445 90)
			(size 0.1397 0.1397)
			(layers "F.Cu" "F.Mask" "F.Paste")
			(net "8644_CBL_PRSNT_R_5")
			(options
				(clearance outline)
				(anchor circle)
			)
			(primitives
				(gr_poly
					(pts
						(arc
							(start -0.1778 -0.2794)
							(mid -0.249642 -0.249642)
							(end -0.2794 -0.1778)
						)
						(arc
							(start -0.2794 0.1778)
							(mid -0.249642 0.249642)
							(end -0.1778 0.2794)
						)
						(arc
							(start 0.1778 0.2794)
							(mid 0.249642 0.249642)
							(end 0.2794 0.1778)
						)
						(arc
							(start 0.2794 -0.1778)
							(mid 0.249642 -0.249642)
							(end 0.1778 -0.2794)
						)
					)
					(width 0)
					(fill yes)
				)
			)
		)
	)
)
